(kicad_pcb
	(version 20260206)
	(generator "pcbnew")
	(generator_version "10.0")
	(general
		(thickness 1.6)
		(legacy_teardrops no)
	)
	(paper "A4")
	(title_block
		(title "04192023_DAF0TMB3IC0_F0TG_MB_C_brd_V02_OCP.brd")
		(comment 1 "Grand Teton / footprints 5008-5014 of 8354")
	)
	(layers
		(0 "F.Cu" signal "TOP")
		(4 "In1.Cu" signal "GND")
		(6 "In2.Cu" signal "IN1")
		(8 "In3.Cu" signal "GND1")
		(10 "In4.Cu" signal "IN2")
		(12 "In5.Cu" signal "GND2")
		(14 "In6.Cu" signal "IN3")
		(16 "In7.Cu" signal "GND3")
		(18 "In8.Cu" signal "VCC")
		(20 "In9.Cu" signal "VCC1")
		(22 "In10.Cu" signal "GND4")
		(24 "In11.Cu" signal "IN4")
		(26 "In12.Cu" signal "GND5")
		(28 "In13.Cu" signal "IN5")
		(30 "In14.Cu" signal "GND6")
		(32 "In15.Cu" signal "IN6")
		(34 "In16.Cu" signal "GND7")
		(2 "B.Cu" signal "BOTTOM")
		(9 "F.Adhes" user "F.Adhesive")
		(11 "B.Adhes" user "B.Adhesive")
		(13 "F.Paste" user "Package Geometry/Pastemask Top")
		(15 "B.Paste" user "Package Geometry/Pastemask Bottom")
		(5 "F.SilkS" user "Ref Des/Silkscreen Top")
		(7 "B.SilkS" user "Ref Des/Silkscreen Bottom")
		(1 "F.Mask" user "Board Geometry/Soldermask Top")
		(3 "B.Mask" user "Board Geometry/Soldermask Bottom")
		(17 "Dwgs.User" user "User.Drawings")
		(19 "Cmts.User" user "User.Comments")
		(21 "Eco1.User" user "User.Eco1")
		(23 "Eco2.User" user "User.Eco2")
		(25 "Edge.Cuts" user "Board Geometry/Outline")
		(27 "Margin" user)
		(31 "F.CrtYd" user "Package Geometry/Place Bound Top")
		(29 "B.CrtYd" user "Package Geometry/Place Bound Bottom")
		(35 "F.Fab" user "Ref Des/Assembly Top")
		(33 "B.Fab" user "Ref Des/Assembly Bottom")
	)
	(footprint ""
		(layer "B.Cu")
		(at 49.300384 -408.517344 90)
		(property "Reference" "C6662"
			(at 0 0 90)
			(layer "B.SilkS")
			(hide yes)
			(effects
				(font
					(size 1.27 1.27)
				)
				(justify mirror)
			)
		)
		(property "Value" ""
			(at 0 0 90)
			(layer "B.Fab")
			(effects
				(font
					(size 1.27 1.27)
				)
				(justify mirror)
			)
		)
		(duplicate_pad_numbers_are_jumpers no)
		(fp_line
			(start 0.299974 -0.150114)
			(end -0.299974 -0.150114)
			(stroke
				(width 0.1)
				(type default)
			)
			(layer "B.Fab")
		)
		(fp_line
			(start -0.299974 -0.150114)
			(end -0.299974 0.150114)
			(stroke
				(width 0.1)
				(type default)
			)
			(layer "B.Fab")
		)
		(fp_line
			(start 0.299974 0.150114)
			(end 0.299974 -0.150114)
			(stroke
				(width 0.1)
				(type default)
			)
			(layer "B.Fab")
		)
		(fp_line
			(start -0.299974 0.150114)
			(end 0.299974 0.150114)
			(stroke
				(width 0.1)
				(type default)
			)
			(layer "B.Fab")
		)
		(pad "1" smd rect
			(at 0.2667 0 270)
			(size 0.3048 0.381)
			(layers "B.Cu" "B.Mask" "B.Paste")
			(net "P5E_CPU1_P1_TX_BUF_C_DN<0>")
		)
		(pad "2" smd rect
			(at -0.2667 0 270)
			(size 0.3048 0.381)
			(layers "B.Cu" "B.Mask" "B.Paste")
			(net "P5E_CPU1_P1_TX_BUF_DN<0>")
		)
	)
	(footprint ""
		(layer "B.Cu")
		(at 132.478526 -386.766562 90)
		(property "Reference" "C448"
			(at 0 0 90)
			(layer "B.SilkS")
			(hide yes)
			(effects
				(font
					(size 1.27 1.27)
				)
				(justify mirror)
			)
		)
		(property "Value" ""
			(at 0 0 90)
			(layer "B.Fab")
			(effects
				(font
					(size 1.27 1.27)
				)
				(justify mirror)
			)
		)
		(duplicate_pad_numbers_are_jumpers no)
		(fp_line
			(start 0.299974 -0.150114)
			(end -0.299974 -0.150114)
			(stroke
				(width 0.1)
				(type default)
			)
			(layer "B.Fab")
		)
		(fp_line
			(start -0.299974 -0.150114)
			(end -0.299974 0.150114)
			(stroke
				(width 0.1)
				(type default)
			)
			(layer "B.Fab")
		)
		(fp_line
			(start 0.299974 0.150114)
			(end 0.299974 -0.150114)
			(stroke
				(width 0.1)
				(type default)
			)
			(layer "B.Fab")
		)
		(fp_line
			(start -0.299974 0.150114)
			(end 0.299974 0.150114)
			(stroke
				(width 0.1)
				(type default)
			)
			(layer "B.Fab")
		)
		(pad "1" smd rect
			(at 0.2667 0 270)
			(size 0.3048 0.381)
			(layers "B.Cu" "B.Mask" "B.Paste")
			(net "P0V9_CPU1_RT3_2A")
		)
		(pad "2" smd rect
			(at -0.2667 0 270)
			(size 0.3048 0.381)
			(layers "B.Cu" "B.Mask" "B.Paste")
			(net "GND")
		)
	)
	(footprint ""
		(layer "B.Cu")
		(at 196.064632 -351.201736 90)
		(property "Reference" "PC27"
			(at 0 0 90)
			(layer "B.SilkS")
			(hide yes)
			(effects
				(font
					(size 1.27 1.27)
				)
				(justify mirror)
			)
		)
		(property "Value" ""
			(at 0 0 90)
			(layer "B.Fab")
			(effects
				(font
					(size 1.27 1.27)
				)
				(justify mirror)
			)
		)
		(duplicate_pad_numbers_are_jumpers no)
		(fp_line
			(start 1.524 -0.762)
			(end -1.524 -0.762)
			(stroke
				(width 0.1524)
				(type default)
			)
			(layer "B.SilkS")
		)
		(fp_line
			(start -1.524 -0.762)
			(end -1.524 0.762)
			(stroke
				(width 0.1524)
				(type default)
			)
			(layer "B.SilkS")
		)
		(fp_line
			(start 1.524 0.762)
			(end 1.524 -0.762)
			(stroke
				(width 0.1524)
				(type default)
			)
			(layer "B.SilkS")
		)
		(fp_line
			(start -1.524 0.762)
			(end 1.524 0.762)
			(stroke
				(width 0.1524)
				(type default)
			)
			(layer "B.SilkS")
		)
		(fp_line
			(start 1.1049 -0.724916)
			(end 1.1049 0.724916)
			(stroke
				(width 0.1)
				(type default)
			)
			(layer "B.Fab")
		)
		(fp_line
			(start -1.1049 -0.724916)
			(end 1.1049 -0.724916)
			(stroke
				(width 0.1)
				(type default)
			)
			(layer "B.Fab")
		)
		(fp_line
			(start 1.1049 0.724916)
			(end -1.1049 0.724916)
			(stroke
				(width 0.1)
				(type default)
			)
			(layer "B.Fab")
		)
		(fp_line
			(start -1.1049 0.724916)
			(end -1.1049 -0.724916)
			(stroke
				(width 0.1)
				(type default)
			)
			(layer "B.Fab")
		)
		(pad "1" smd rect
			(at 0.889 0 90)
			(size 1.016 1.27)
			(layers "B.Cu" "B.Mask" "B.Paste")
			(net "SW_P12V_AUX_PVDD11_S3_P1_FLT")
		)
		(pad "2" smd rect
			(at -0.889 0 90)
			(size 1.016 1.27)
			(layers "B.Cu" "B.Mask" "B.Paste")
			(net "GND")
		)
	)
	(footprint ""
		(layer "B.Cu")
		(at 34.570162 -347.780356 -90)
		(property "Reference" "PR371"
			(at 0 0 90)
			(layer "B.SilkS")
			(hide yes)
			(effects
				(font
					(size 1.27 1.27)
				)
				(justify mirror)
			)
		)
		(property "Value" ""
			(at 0 0 90)
			(layer "B.Fab")
			(effects
				(font
					(size 1.27 1.27)
				)
				(justify mirror)
			)
		)
		(duplicate_pad_numbers_are_jumpers no)
		(fp_line
			(start -0.7874 0.4064)
			(end 0.7874 0.4064)
			(stroke
				(width 0.1524)
				(type default)
			)
			(layer "B.SilkS")
		)
		(fp_line
			(start 0.7874 0.4064)
			(end 0.7874 -0.4064)
			(stroke
				(width 0.1524)
				(type default)
			)
			(layer "B.SilkS")
		)
		(fp_line
			(start -0.7874 -0.4064)
			(end -0.7874 0.4064)
			(stroke
				(width 0.1524)
				(type default)
			)
			(layer "B.SilkS")
		)
		(fp_line
			(start 0.7874 -0.4064)
			(end -0.7874 -0.4064)
			(stroke
				(width 0.1524)
				(type default)
			)
			(layer "B.SilkS")
		)
		(fp_line
			(start -0.67945 0.3048)
			(end -0.120396 0.3048)
			(stroke
				(width 0.1)
				(type default)
			)
			(layer "B.Fab")
		)
		(fp_line
			(start -0.120396 0.3048)
			(end -0.120396 0.2794)
			(stroke
				(width 0.1)
				(type default)
			)
			(layer "B.Fab")
		)
		(fp_line
			(start 0.12065 0.3048)
			(end 0.67945 0.3048)
			(stroke
				(width 0.1)
				(type default)
			)
			(layer "B.Fab")
		)
		(fp_line
			(start 0.67945 0.3048)
			(end 0.67945 -0.305054)
			(stroke
				(width 0.1)
				(type default)
			)
			(layer "B.Fab")
		)
		(fp_line
			(start -0.120396 0.2794)
			(end 0.12065 0.2794)
			(stroke
				(width 0.1)
				(type default)
			)
			(layer "B.Fab")
		)
		(fp_line
			(start 0.12065 0.2794)
			(end 0.12065 0.3048)
			(stroke
				(width 0.1)
				(type default)
			)
			(layer "B.Fab")
		)
		(fp_line
			(start -0.12065 -0.2794)
			(end -0.12065 -0.3048)
			(stroke
				(width 0.1)
				(type default)
			)
			(layer "B.Fab")
		)
		(fp_line
			(start 0.12065 -0.2794)
			(end -0.12065 -0.2794)
			(stroke
				(width 0.1)
				(type default)
			)
			(layer "B.Fab")
		)
		(fp_line
			(start -0.67945 -0.3048)
			(end -0.67945 0.3048)
			(stroke
				(width 0.1)
				(type default)
			)
			(layer "B.Fab")
		)
		(fp_line
			(start -0.12065 -0.3048)
			(end -0.67945 -0.3048)
			(stroke
				(width 0.1)
				(type default)
			)
			(layer "B.Fab")
		)
		(fp_line
			(start 0.12065 -0.305054)
			(end 0.12065 -0.2794)
			(stroke
				(width 0.1)
				(type default)
			)
			(layer "B.Fab")
		)
		(fp_line
			(start 0.67945 -0.305054)
			(end 0.12065 -0.305054)
			(stroke
				(width 0.1)
				(type default)
			)
			(layer "B.Fab")
		)
		(pad "1" smd circle
			(at 0.40005 0 90)
			(size 0 0)
			(layers "B.Cu" "B.Mask" "B.Paste")
			(net "PVDDCR_CPU1_P1_PVCC")
		)
		(pad "2" smd circle
			(at -0.40005 0 90)
			(size 0 0)
			(layers "B.Cu" "B.Mask" "B.Paste")
			(net "PVDDIO_P1_VCC3")
		)
	)
	(footprint ""
		(layer "B.Cu")
		(at 216.25306 -78.448408 180)
		(property "Reference" "R3212"
			(at 0 0 0)
			(layer "B.SilkS")
			(hide yes)
			(effects
				(font
					(size 1.27 1.27)
				)
				(justify mirror)
			)
		)
		(property "Value" ""
			(at 0 0 0)
			(layer "B.Fab")
			(effects
				(font
					(size 1.27 1.27)
				)
				(justify mirror)
			)
		)
		(duplicate_pad_numbers_are_jumpers no)
		(fp_line
			(start 0.7874 0.4064)
			(end 0.7874 -0.4064)
			(stroke
				(width 0.1524)
				(type default)
			)
			(layer "B.SilkS")
		)
		(fp_line
			(start 0.7874 -0.4064)
			(end -0.7874 -0.4064)
			(stroke
				(width 0.1524)
				(type default)
			)
			(layer "B.SilkS")
		)
		(fp_line
			(start -0.7874 0.4064)
			(end 0.7874 0.4064)
			(stroke
				(width 0.1524)
				(type default)
			)
			(layer "B.SilkS")
		)
		(fp_line
			(start -0.7874 -0.4064)
			(end -0.7874 0.4064)
			(stroke
				(width 0.1524)
				(type default)
			)
			(layer "B.SilkS")
		)
		(fp_line
			(start 0.67945 0.3048)
			(end 0.67945 -0.305054)
			(stroke
				(width 0.1)
				(type default)
			)
			(layer "B.Fab")
		)
		(fp_line
			(start 0.67945 -0.305054)
			(end 0.12065 -0.305054)
			(stroke
				(width 0.1)
				(type default)
			)
			(layer "B.Fab")
		)
		(fp_line
			(start 0.12065 0.3048)
			(end 0.67945 0.3048)
			(stroke
				(width 0.1)
				(type default)
			)
			(layer "B.Fab")
		)
		(fp_line
			(start 0.12065 0.2794)
			(end 0.12065 0.3048)
			(stroke
				(width 0.1)
				(type default)
			)
			(layer "B.Fab")
		)
		(fp_line
			(start 0.12065 -0.2794)
			(end -0.12065 -0.2794)
			(stroke
				(width 0.1)
				(type default)
			)
			(layer "B.Fab")
		)
		(fp_line
			(start 0.12065 -0.305054)
			(end 0.12065 -0.2794)
			(stroke
				(width 0.1)
				(type default)
			)
			(layer "B.Fab")
		)
		(fp_line
			(start -0.120396 0.3048)
			(end -0.120396 0.2794)
			(stroke
				(width 0.1)
				(type default)
			)
			(layer "B.Fab")
		)
		(fp_line
			(start -0.120396 0.2794)
			(end 0.12065 0.2794)
			(stroke
				(width 0.1)
				(type default)
			)
			(layer "B.Fab")
		)
		(fp_line
			(start -0.12065 -0.2794)
			(end -0.12065 -0.3048)
			(stroke
				(width 0.1)
				(type default)
			)
			(layer "B.Fab")
		)
		(fp_line
			(start -0.12065 -0.3048)
			(end -0.67945 -0.3048)
			(stroke
				(width 0.1)
				(type default)
			)
			(layer "B.Fab")
		)
		(fp_line
			(start -0.67945 0.3048)
			(end -0.120396 0.3048)
			(stroke
				(width 0.1)
				(type default)
			)
			(layer "B.Fab")
		)
		(fp_line
			(start -0.67945 -0.3048)
			(end -0.67945 0.3048)
			(stroke
				(width 0.1)
				(type default)
			)
			(layer "B.Fab")
		)
		(pad "1" smd circle
			(at 0.40005 0)
			(size 0 0)
			(layers "B.Cu" "B.Mask" "B.Paste")
			(net "NCSI_BMC_RXD1_R1")
		)
		(pad "2" smd circle
			(at -0.40005 0)
			(size 0 0)
			(layers "B.Cu" "B.Mask" "B.Paste")
			(net "RMII_OCP_BMC_RXD_1")
		)
	)
	(footprint ""
		(layer "B.Cu")
		(at 91.508834 -305.406552 180)
		(property "Reference" "R515"
			(at 0 0 0)
			(layer "B.SilkS")
			(hide yes)
			(effects
				(font
					(size 1.27 1.27)
				)
				(justify mirror)
			)
		)
		(property "Value" ""
			(at 0 0 0)
			(layer "B.Fab")
			(effects
				(font
					(size 1.27 1.27)
				)
				(justify mirror)
			)
		)
		(duplicate_pad_numbers_are_jumpers no)
		(fp_line
			(start 0.7874 0.4064)
			(end 0.7874 -0.4064)
			(stroke
				(width 0.1524)
				(type default)
			)
			(layer "B.SilkS")
		)
		(fp_line
			(start 0.7874 -0.4064)
			(end -0.7874 -0.4064)
			(stroke
				(width 0.1524)
				(type default)
			)
			(layer "B.SilkS")
		)
		(fp_line
			(start -0.7874 0.4064)
			(end 0.7874 0.4064)
			(stroke
				(width 0.1524)
				(type default)
			)
			(layer "B.SilkS")
		)
		(fp_line
			(start -0.7874 -0.4064)
			(end -0.7874 0.4064)
			(stroke
				(width 0.1524)
				(type default)
			)
			(layer "B.SilkS")
		)
		(fp_line
			(start 0.67945 0.3048)
			(end 0.67945 -0.305054)
			(stroke
				(width 0.1)
				(type default)
			)
			(layer "B.Fab")
		)
		(fp_line
			(start 0.67945 -0.305054)
			(end 0.12065 -0.305054)
			(stroke
				(width 0.1)
				(type default)
			)
			(layer "B.Fab")
		)
		(fp_line
			(start 0.12065 0.3048)
			(end 0.67945 0.3048)
			(stroke
				(width 0.1)
				(type default)
			)
			(layer "B.Fab")
		)
		(fp_line
			(start 0.12065 0.2794)
			(end 0.12065 0.3048)
			(stroke
				(width 0.1)
				(type default)
			)
			(layer "B.Fab")
		)
		(fp_line
			(start 0.12065 -0.2794)
			(end -0.12065 -0.2794)
			(stroke
				(width 0.1)
				(type default)
			)
			(layer "B.Fab")
		)
		(fp_line
			(start 0.12065 -0.305054)
			(end 0.12065 -0.2794)
			(stroke
				(width 0.1)
				(type default)
			)
			(layer "B.Fab")
		)
		(fp_line
			(start -0.120396 0.3048)
			(end -0.120396 0.2794)
			(stroke
				(width 0.1)
				(type default)
			)
			(layer "B.Fab")
		)
		(fp_line
			(start -0.120396 0.2794)
			(end 0.12065 0.2794)
			(stroke
				(width 0.1)
				(type default)
			)
			(layer "B.Fab")
		)
		(fp_line
			(start -0.12065 -0.2794)
			(end -0.12065 -0.3048)
			(stroke
				(width 0.1)
				(type default)
			)
			(layer "B.Fab")
		)
		(fp_line
			(start -0.12065 -0.3048)
			(end -0.67945 -0.3048)
			(stroke
				(width 0.1)
				(type default)
			)
			(layer "B.Fab")
		)
		(fp_line
			(start -0.67945 0.3048)
			(end -0.120396 0.3048)
			(stroke
				(width 0.1)
				(type default)
			)
			(layer "B.Fab")
		)
		(fp_line
			(start -0.67945 -0.3048)
			(end -0.67945 0.3048)
			(stroke
				(width 0.1)
				(type default)
			)
			(layer "B.Fab")
		)
		(pad "1" smd circle
			(at 0.40005 0)
			(size 0 0)
			(layers "B.Cu" "B.Mask" "B.Paste")
			(net "P3V3_AUX")
		)
		(pad "2" smd circle
			(at -0.40005 0)
			(size 0 0)
			(layers "B.Cu" "B.Mask" "B.Paste")
			(net "CPU1_SP5R3")
		)
	)
	(footprint ""
		(layer "B.Cu")
		(at 216.123774 -323.588634 180)
		(property "Reference" "R1243"
			(at 0 0 0)
			(layer "B.SilkS")
			(hide yes)
			(effects
				(font
					(size 1.27 1.27)
				)
				(justify mirror)
			)
		)
		(property "Value" ""
			(at 0 0 0)
			(layer "B.Fab")
			(effects
				(font
					(size 1.27 1.27)
				)
				(justify mirror)
			)
		)
		(duplicate_pad_numbers_are_jumpers no)
		(fp_line
			(start 0.7874 0.4064)
			(end 0.7874 -0.4064)
			(stroke
				(width 0.1524)
				(type default)
			)
			(layer "B.SilkS")
		)
		(fp_line
			(start 0.7874 -0.4064)
			(end -0.7874 -0.4064)
			(stroke
				(width 0.1524)
				(type default)
			)
			(layer "B.SilkS")
		)
		(fp_line
			(start -0.7874 0.4064)
			(end 0.7874 0.4064)
			(stroke
				(width 0.1524)
				(type default)
			)
			(layer "B.SilkS")
		)
		(fp_line
			(start -0.7874 -0.4064)
			(end -0.7874 0.4064)
			(stroke
				(width 0.1524)
				(type default)
			)
			(layer "B.SilkS")
		)
		(fp_line
			(start 0.67945 0.3048)
			(end 0.67945 -0.305054)
			(stroke
				(width 0.1)
				(type default)
			)
			(layer "B.Fab")
		)
		(fp_line
			(start 0.67945 -0.305054)
			(end 0.12065 -0.305054)
			(stroke
				(width 0.1)
				(type default)
			)
			(layer "B.Fab")
		)
		(fp_line
			(start 0.12065 0.3048)
			(end 0.67945 0.3048)
			(stroke
				(width 0.1)
				(type default)
			)
			(layer "B.Fab")
		)
		(fp_line
			(start 0.12065 0.2794)
			(end 0.12065 0.3048)
			(stroke
				(width 0.1)
				(type default)
			)
			(layer "B.Fab")
		)
		(fp_line
			(start 0.12065 -0.2794)
			(end -0.12065 -0.2794)
			(stroke
				(width 0.1)
				(type default)
			)
			(layer "B.Fab")
		)
		(fp_line
			(start 0.12065 -0.305054)
			(end 0.12065 -0.2794)
			(stroke
				(width 0.1)
				(type default)
			)
			(layer "B.Fab")
		)
		(fp_line
			(start -0.120396 0.3048)
			(end -0.120396 0.2794)
			(stroke
				(width 0.1)
				(type default)
			)
			(layer "B.Fab")
		)
		(fp_line
			(start -0.120396 0.2794)
			(end 0.12065 0.2794)
			(stroke
				(width 0.1)
				(type default)
			)
			(layer "B.Fab")
		)
		(fp_line
			(start -0.12065 -0.2794)
			(end -0.12065 -0.3048)
			(stroke
				(width 0.1)
				(type default)
			)
			(layer "B.Fab")
		)
		(fp_line
			(start -0.12065 -0.3048)
			(end -0.67945 -0.3048)
			(stroke
				(width 0.1)
				(type default)
			)
			(layer "B.Fab")
		)
		(fp_line
			(start -0.67945 0.3048)
			(end -0.120396 0.3048)
			(stroke
				(width 0.1)
				(type default)
			)
			(layer "B.Fab")
		)
		(fp_line
			(start -0.67945 -0.3048)
			(end -0.67945 0.3048)
			(stroke
				(width 0.1)
				(type default)
			)
			(layer "B.Fab")
		)
		(pad "1" smd circle
			(at 0.40005 0)
			(size 0 0)
			(layers "B.Cu" "B.Mask" "B.Paste")
			(net "SMB_ADC_SDA_R")
		)
		(pad "2" smd circle
			(at -0.40005 0)
			(size 0 0)
			(layers "B.Cu" "B.Mask" "B.Paste")
			(net "SMB_SEN_TIC_2_3V3AUX_SDA")
		)
	)
)
